# BASEBOARD_FAB2 (Tioga Pass) — schematic netlist excerpt (pin names and nets, part order shuffled) for the footprints in the layout excerpt that follows; sources: Cadence DE-HDL packaged netlist, KiCad conversion of Wiwynn_Tioga_Pass_MB.brd

R1R19  RES  2.21K 1% CHIP  pkg 0402  page 188 : A = P3V3_STBY ; B = SMB_PCH_MEZZ_LOM0_SDA
R9L9  RES  0.0 5% CHIP  pkg 0402  page 227 : A = VR_PVDDQ_KLM_PH1_VCIN ; B = P5V_STBY
C3M46  CAP_A  1.0UF 6.3V 10% X6S  pkg 0402V  page 194 : A = PVCCIOMCP_CPU0 ; B = GND

(kicad_pcb
	(version 20260206)
	(generator "pcbnew")
	(generator_version "10.0")
	(general
		(thickness 1.6)
		(legacy_teardrops no)
	)
	(paper "A4")
	(title_block
		(title "Wiwynn_Tioga_Pass_MB.brd")
		(comment 1 "Tioga Pass / footprints 2540-2542 of 4770")
	)
	(layers
		(0 "F.Cu" signal "TOP")
		(4 "In1.Cu" signal "L2GND")
		(6 "In2.Cu" signal "L3")
		(8 "In3.Cu" signal "L4GND")
		(10 "In4.Cu" signal "L5")
		(12 "In5.Cu" signal "L6GND")
		(14 "In6.Cu" signal "L7VCC")
		(16 "In7.Cu" signal "L8VCC")
		(18 "In8.Cu" signal "L9GND")
		(20 "In9.Cu" signal "L10")
		(22 "In10.Cu" signal "L11GND")
		(24 "In11.Cu" signal "L12")
		(26 "In12.Cu" signal "L13GND")
		(2 "B.Cu" signal "BOTTOM")
		(9 "F.Adhes" user "F.Adhesive")
		(11 "B.Adhes" user "B.Adhesive")
		(13 "F.Paste" user "Package Geometry/Pastemask Top")
		(15 "B.Paste" user "Package Geometry/Pastemask Bottom")
		(5 "F.SilkS" user "Ref Des/Silkscreen Top")
		(7 "B.SilkS" user "Ref Des/Silkscreen Bottom")
		(1 "F.Mask" user "Board Geometry/Soldermask Top")
		(3 "B.Mask" user "Board Geometry/Soldermask Bottom")
		(17 "Dwgs.User" user "User.Drawings")
		(19 "Cmts.User" user "User.Comments")
		(21 "Eco1.User" user "User.Eco1")
		(23 "Eco2.User" user "User.Eco2")
		(25 "Edge.Cuts" user "Board Geometry/Outline")
		(27 "Margin" user)
		(31 "F.CrtYd" user "Package Geometry/Place Bound Top")
		(29 "B.CrtYd" user "Package Geometry/Place Bound Bottom")
		(35 "F.Fab" user "Ref Des/Assembly Top")
		(33 "B.Fab" user "Ref Des/Assembly Bottom")
	)
	(footprint ""
		(layer "B.Cu")
		(at 0.889 -135.763 90)
		(property "Reference" "R9L9"
			(at 0 0 90)
			(layer "B.SilkS")
			(hide yes)
			(effects
				(font
					(size 1.27 1.27)
				)
				(justify mirror)
			)
		)
		(property "Value" ""
			(at 0 0 90)
			(layer "B.Fab")
			(effects
				(font
					(size 1.27 1.27)
				)
				(justify mirror)
			)
		)
		(duplicate_pad_numbers_are_jumpers no)
		(fp_rect
			(start 0.2794 -0.1016)
			(end -0.2794 0.9906)
			(stroke
				(width 0)
				(type default)
			)
			(fill no)
			(layer "B.CrtYd")
		)
		(fp_line
			(start 0.2794 -0.1016)
			(end 0.2794 0.9906)
			(stroke
				(width 0.1)
				(type default)
			)
			(layer "B.Fab")
		)
		(fp_line
			(start -0.2794 -0.1016)
			(end 0.2794 -0.1016)
			(stroke
				(width 0.1)
				(type default)
			)
			(layer "B.Fab")
		)
		(fp_line
			(start 0.2794 0.9906)
			(end -0.2794 0.9906)
			(stroke
				(width 0.1)
				(type default)
			)
			(layer "B.Fab")
		)
		(fp_line
			(start -0.2794 0.9906)
			(end -0.2794 -0.1016)
			(stroke
				(width 0.1)
				(type default)
			)
			(layer "B.Fab")
		)
		(pad "1" smd rect
			(at 0 0 270)
			(size 0.508 0.508)
			(layers "B.Cu" "B.Mask" "B.Paste")
			(net "VR_PVDDQ_KLM_PH1_VCIN")
		)
		(pad "2" smd rect
			(at 0 0.889 270)
			(size 0.508 0.508)
			(layers "B.Cu" "B.Mask" "B.Paste")
			(net "P5V_STBY")
		)
		(zone
			(layer "B.Cu")
			(hatch none 0.5)
			(connect_pads
				(clearance 0)
			)
			(min_thickness 0.25)
			(keepout
				(tracks allowed)
				(vias not_allowed)
				(pads allowed)
				(copperpour not_allowed)
				(footprints allowed)
			)
			(placement
				(enabled no)
				(sheetname "")
			)
			(fill
				(thermal_gap 0.5)
				(thermal_bridge_width 0.5)
				(island_removal_mode 0)
			)
			(polygon
				(pts
					(xy 1.143 -136.017) (xy 1.143 -135.509) (xy 1.524 -135.509) (xy 1.524 -136.017)
				)
			)
		)
		(zone
			(layer "B.Cu")
			(hatch none 0.5)
			(connect_pads
				(clearance 0)
			)
			(min_thickness 0.25)
			(keepout
				(tracks not_allowed)
				(vias allowed)
				(pads allowed)
				(copperpour not_allowed)
				(footprints allowed)
			)
			(placement
				(enabled no)
				(sheetname "")
			)
			(fill
				(thermal_gap 0.5)
				(thermal_bridge_width 0.5)
				(island_removal_mode 0)
			)
			(polygon
				(pts
					(xy 1.143 -136.017) (xy 1.143 -135.509) (xy 1.524 -135.509) (xy 1.524 -136.017)
				)
			)
		)
	)
	(footprint ""
		(layer "B.Cu")
		(at 345.8972 -112.7252 -90)
		(property "Reference" "C3M46"
			(at 0 0 90)
			(layer "B.SilkS")
			(hide yes)
			(effects
				(font
					(size 1.27 1.27)
				)
				(justify mirror)
			)
		)
		(property "Value" ""
			(at 0 0 90)
			(layer "B.Fab")
			(effects
				(font
					(size 1.27 1.27)
				)
				(justify mirror)
			)
		)
		(duplicate_pad_numbers_are_jumpers no)
		(fp_poly
			(pts
				(xy -0.3048 -0.1016) (xy -0.3048 0.9906) (xy 0.3048 0.9906) (xy 0.3048 -0.1016)
			)
			(stroke
				(width 0)
				(type default)
			)
			(fill no)
			(layer "B.CrtYd")
		)
		(fp_line
			(start -0.3048 0.9906)
			(end -0.3048 -0.1016)
			(stroke
				(width 0.1)
				(type default)
			)
			(layer "B.Fab")
		)
		(fp_line
			(start 0.3048 0.9906)
			(end -0.3048 0.9906)
			(stroke
				(width 0.1)
				(type default)
			)
			(layer "B.Fab")
		)
		(fp_line
			(start -0.3048 -0.1016)
			(end 0.3048 -0.1016)
			(stroke
				(width 0.1)
				(type default)
			)
			(layer "B.Fab")
		)
		(fp_line
			(start 0.3048 -0.1016)
			(end 0.3048 0.9906)
			(stroke
				(width 0.1)
				(type default)
			)
			(layer "B.Fab")
		)
		(pad "1" smd rect
			(at 0 0 90)
			(size 0.508 0.508)
			(layers "B.Cu" "B.Mask" "B.Paste")
			(net "PVCCIOMCP_CPU0")
		)
		(pad "2" smd rect
			(at 0 0.889 90)
			(size 0.508 0.508)
			(layers "B.Cu" "B.Mask" "B.Paste")
			(net "GND")
		)
		(zone
			(layer "B.Cu")
			(hatch none 0.5)
			(connect_pads
				(clearance 0)
			)
			(min_thickness 0.25)
			(keepout
				(tracks not_allowed)
				(vias allowed)
				(pads allowed)
				(copperpour not_allowed)
				(footprints allowed)
			)
			(placement
				(enabled no)
				(sheetname "")
			)
			(fill
				(thermal_gap 0.5)
				(thermal_bridge_width 0.5)
				(island_removal_mode 0)
			)
			(polygon
				(pts
					(xy 345.2622 -112.4712) (xy 345.2622 -112.9792) (xy 345.6432 -112.9792) (xy 345.6432 -112.4712)
				)
			)
		)
		(zone
			(layer "B.Cu")
			(hatch none 0.5)
			(connect_pads
				(clearance 0)
			)
			(min_thickness 0.25)
			(keepout
				(tracks allowed)
				(vias not_allowed)
				(pads allowed)
				(copperpour not_allowed)
				(footprints allowed)
			)
			(placement
				(enabled no)
				(sheetname "")
			)
			(fill
				(thermal_gap 0.5)
				(thermal_bridge_width 0.5)
				(island_removal_mode 0)
			)
			(polygon
				(pts
					(xy 345.6432 -112.4712) (xy 345.6432 -112.9792) (xy 345.2622 -112.9792) (xy 345.2622 -112.4712)
				)
			)
		)
	)
	(footprint ""
		(layer "B.Cu")
		(at 470.027 -60.198 -90)
		(property "Reference" "R1R19"
			(at 0 0 90)
			(layer "B.SilkS")
			(hide yes)
			(effects
				(font
					(size 1.27 1.27)
				)
				(justify mirror)
			)
		)
		(property "Value" ""
			(at 0 0 90)
			(layer "B.Fab")
			(effects
				(font
					(size 1.27 1.27)
				)
				(justify mirror)
			)
		)
		(duplicate_pad_numbers_are_jumpers no)
		(fp_poly
			(pts
				(xy 0.2794 -0.1016) (xy -0.2794 -0.1016) (xy -0.2794 0.9906) (xy 0.2794 0.9906)
			)
			(stroke
				(width 0)
				(type default)
			)
			(fill no)
			(layer "B.CrtYd")
		)
		(fp_line
			(start -0.2794 0.9906)
			(end -0.2794 -0.1016)
			(stroke
				(width 0.1)
				(type default)
			)
			(layer "B.Fab")
		)
		(fp_line
			(start 0.2794 0.9906)
			(end -0.2794 0.9906)
			(stroke
				(width 0.1)
				(type default)
			)
			(layer "B.Fab")
		)
		(fp_line
			(start -0.2794 -0.1016)
			(end 0.2794 -0.1016)
			(stroke
				(width 0.1)
				(type default)
			)
			(layer "B.Fab")
		)
		(fp_line
			(start 0.2794 -0.1016)
			(end 0.2794 0.9906)
			(stroke
				(width 0.1)
				(type default)
			)
			(layer "B.Fab")
		)
		(pad "1" smd rect
			(at 0 0 90)
			(size 0.508 0.508)
			(layers "B.Cu" "B.Mask" "B.Paste")
			(net "P3V3_STBY")
		)
		(pad "2" smd rect
			(at 0 0.889 90)
			(size 0.508 0.508)
			(layers "B.Cu" "B.Mask" "B.Paste")
			(net "SMB_PCH_MEZZ_LOM0_SDA")
		)
		(zone
			(layer "B.Cu")
			(hatch none 0.5)
			(connect_pads
				(clearance 0)
			)
			(min_thickness 0.25)
			(keepout
				(tracks not_allowed)
				(vias allowed)
				(pads allowed)
				(copperpour not_allowed)
				(footprints allowed)
			)
			(placement
				(enabled no)
				(sheetname "")
			)
			(fill
				(thermal_gap 0.5)
				(thermal_bridge_width 0.5)
				(island_removal_mode 0)
			)
			(polygon
				(pts
					(xy 469.392 -59.944) (xy 469.392 -60.452) (xy 469.773 -60.452) (xy 469.773 -59.944)
				)
			)
		)
		(zone
			(layer "B.Cu")
			(hatch none 0.5)
			(connect_pads
				(clearance 0)
			)
			(min_thickness 0.25)
			(keepout
				(tracks allowed)
				(vias not_allowed)
				(pads allowed)
				(copperpour not_allowed)
				(footprints allowed)
			)
			(placement
				(enabled no)
				(sheetname "")
			)
			(fill
				(thermal_gap 0.5)
				(thermal_bridge_width 0.5)
				(island_removal_mode 0)
			)
			(polygon
				(pts
					(xy 469.773 -59.944) (xy 469.773 -60.452) (xy 469.392 -60.452) (xy 469.392 -59.944)
				)
			)
		)
	)
)
